FILE_TYPE=LIBRARY_PARTS;
primitive '2N7002A7';
  pin
    'G':
      PIN_NUMBER='(G)';
      INPUT_LOAD='(-0.01,0.01)';
    'D':
      PIN_NUMBER='(D)';
      BIDIRECTIONAL='TRUE';
      INPUT_LOAD='(-0.01,0.01)';
      OUTPUT_LOAD='(1.0,-1.0)';
    'S':
      PIN_NUMBER='(S)';
      BIDIRECTIONAL='TRUE';
      INPUT_LOAD='(-0.01,0.01)';
      OUTPUT_LOAD='(1.0,-1.0)';
  end_pin;
  body
    PART_NAME='2N7002A7';
    BODY_NAME='2N7002A7';
    PHYS_DES_PREFIX='Q';
    CLASS='DISCRETE';
  end_body;
end_primitive;

END.
